(kicad_pcb
	(version 20260206)
	(generator "pcbnew")
	(generator_version "10.0")
	(general
		(thickness 1.6)
		(legacy_teardrops no)
	)
	(paper "A4")
	(title_block
		(title "Wiwynn_Tioga_Pass_MB.brd")
		(comment 1 "Tioga Pass / footprints 1942-1949 of 4770")
	)
	(layers
		(0 "F.Cu" signal "TOP")
		(4 "In1.Cu" signal "L2GND")
		(6 "In2.Cu" signal "L3")
		(8 "In3.Cu" signal "L4GND")
		(10 "In4.Cu" signal "L5")
		(12 "In5.Cu" signal "L6GND")
		(14 "In6.Cu" signal "L7VCC")
		(16 "In7.Cu" signal "L8VCC")
		(18 "In8.Cu" signal "L9GND")
		(20 "In9.Cu" signal "L10")
		(22 "In10.Cu" signal "L11GND")
		(24 "In11.Cu" signal "L12")
		(26 "In12.Cu" signal "L13GND")
		(2 "B.Cu" signal "BOTTOM")
		(9 "F.Adhes" user "F.Adhesive")
		(11 "B.Adhes" user "B.Adhesive")
		(13 "F.Paste" user "Package Geometry/Pastemask Top")
		(15 "B.Paste" user "Package Geometry/Pastemask Bottom")
		(5 "F.SilkS" user "Ref Des/Silkscreen Top")
		(7 "B.SilkS" user "Ref Des/Silkscreen Bottom")
		(1 "F.Mask" user "Board Geometry/Soldermask Top")
		(3 "B.Mask" user "Board Geometry/Soldermask Bottom")
		(17 "Dwgs.User" user "User.Drawings")
		(19 "Cmts.User" user "User.Comments")
		(21 "Eco1.User" user "User.Eco1")
		(23 "Eco2.User" user "User.Eco2")
		(25 "Edge.Cuts" user "Board Geometry/Outline")
		(27 "Margin" user)
		(31 "F.CrtYd" user "Package Geometry/Place Bound Top")
		(29 "B.CrtYd" user "Package Geometry/Place Bound Bottom")
		(35 "F.Fab" user "Ref Des/Assembly Top")
		(33 "B.Fab" user "Ref Des/Assembly Bottom")
	)
	(footprint ""
		(layer "F.Cu")
		(at 155.194 -3.302 90)
		(property "Reference" "C3G8"
			(at 0 0 90)
			(layer "F.SilkS")
			(hide yes)
			(effects
				(font
					(size 1.27 1.27)
				)
			)
		)
		(property "Value" ""
			(at 0 0 90)
			(layer "F.Fab")
			(effects
				(font
					(size 1.27 1.27)
				)
			)
		)
		(duplicate_pad_numbers_are_jumpers no)
		(fp_poly
			(pts
				(xy -0.4953 -0.2032) (xy 0.4953 -0.2032) (xy 0.4953 1.6002) (xy -0.4953 1.6002)
			)
			(stroke
				(width 0)
				(type default)
			)
			(fill no)
			(layer "F.CrtYd")
		)
		(fp_line
			(start 0.4953 -0.2032)
			(end 0.4953 1.6002)
			(stroke
				(width 0.1)
				(type default)
			)
			(layer "F.Fab")
		)
		(fp_line
			(start -0.4953 -0.2032)
			(end 0.4953 -0.2032)
			(stroke
				(width 0.1)
				(type default)
			)
			(layer "F.Fab")
		)
		(fp_line
			(start 0.4953 1.6002)
			(end -0.4953 1.6002)
			(stroke
				(width 0.1)
				(type default)
			)
			(layer "F.Fab")
		)
		(fp_line
			(start -0.4953 1.6002)
			(end -0.4953 -0.2032)
			(stroke
				(width 0.1)
				(type default)
			)
			(layer "F.Fab")
		)
		(pad "1" smd rect
			(at 0 0 90)
			(size 0.762 0.889)
			(layers "F.Cu" "F.Mask" "F.Paste")
			(net "PVPP_GHJ")
		)
		(pad "2" smd rect
			(at 0 1.397 90)
			(size 0.762 0.889)
			(layers "F.Cu" "F.Mask" "F.Paste")
			(net "GND")
		)
		(zone
			(layer "F.Cu")
			(hatch none 0.5)
			(connect_pads
				(clearance 0)
			)
			(min_thickness 0.25)
			(keepout
				(tracks not_allowed)
				(vias allowed)
				(pads allowed)
				(copperpour not_allowed)
				(footprints allowed)
			)
			(placement
				(enabled no)
				(sheetname "")
			)
			(fill
				(thermal_gap 0.5)
				(thermal_bridge_width 0.5)
				(island_removal_mode 0)
			)
			(polygon
				(pts
					(xy 155.6385 -2.921) (xy 155.6385 -3.683) (xy 156.1465 -3.683) (xy 156.1465 -2.921)
				)
			)
		)
	)
	(footprint ""
		(layer "F.Cu")
		(at 471.338402 -36.562792 180)
		(property "Reference" "R9F31"
			(at 0 0 180)
			(layer "F.SilkS")
			(hide yes)
			(effects
				(font
					(size 1.27 1.27)
				)
			)
		)
		(property "Value" "*"
			(at 0.064008 -4.108196 180)
			(unlocked yes)
			(layer "F.Fab")
			(hide yes)
			(effects
				(font
					(size 1.27 1.016)
					(thickness 0.1524)
				)
			)
		)
		(property "Device Type" "5K1R2F-2-GP_SMD-RG-5K1R2F-2-GPA"
			(at 0.064008 -5.632196 180)
			(unlocked yes)
			(layer "F.Fab")
			(hide yes)
			(effects
				(font
					(size 1.27 1.016)
					(thickness 0.1524)
				)
			)
		)
		(duplicate_pad_numbers_are_jumpers no)
		(fp_line
			(start 0.508 -0.9398)
			(end -0.508 -0.9398)
			(stroke
				(width 0.1524)
				(type default)
			)
			(layer "F.SilkS")
		)
		(fp_line
			(start -0.508 -0.9398)
			(end -0.508 0.9398)
			(stroke
				(width 0.1524)
				(type default)
			)
			(layer "F.SilkS")
		)
		(fp_rect
			(start -0.508 0.9398)
			(end 0.508 -0.9398)
			(stroke
				(width 0)
				(type default)
			)
			(fill no)
			(layer "F.CrtYd")
		)
		(fp_rect
			(start -0.508 0.9398)
			(end 0.508 -0.9398)
			(stroke
				(width 0)
				(type default)
			)
			(fill no)
			(layer "F.Fab")
		)
		(pad "1" smd custom
			(at 0 -0.4445 180)
			(size 0.1397 0.1397)
			(layers "F.Cu" "F.Mask" "F.Paste")
			(net "P1V2_AUX_BMC")
			(options
				(clearance outline)
				(anchor circle)
			)
			(primitives
				(gr_poly
					(pts
						(arc
							(start -0.1778 -0.2794)
							(mid -0.249642 -0.249642)
							(end -0.2794 -0.1778)
						)
						(arc
							(start -0.2794 0.1778)
							(mid -0.249642 0.249642)
							(end -0.1778 0.2794)
						)
						(arc
							(start 0.1778 0.2794)
							(mid 0.249642 0.249642)
							(end 0.2794 0.1778)
						)
						(arc
							(start 0.2794 -0.1778)
							(mid 0.249642 -0.249642)
							(end 0.1778 -0.2794)
						)
					)
					(width 0)
					(fill yes)
				)
			)
		)
		(pad "2" smd custom
			(at 0 0.4445 180)
			(size 0.1397 0.1397)
			(layers "F.Cu" "F.Mask" "F.Paste")
			(net "VR_P1V2_BMC_STBY_FB")
			(options
				(clearance outline)
				(anchor circle)
			)
			(primitives
				(gr_poly
					(pts
						(arc
							(start -0.1778 -0.2794)
							(mid -0.249642 -0.249642)
							(end -0.2794 -0.1778)
						)
						(arc
							(start -0.2794 0.1778)
							(mid -0.249642 0.249642)
							(end -0.1778 0.2794)
						)
						(arc
							(start 0.1778 0.2794)
							(mid 0.249642 0.249642)
							(end 0.2794 0.1778)
						)
						(arc
							(start 0.2794 -0.1778)
							(mid 0.249642 -0.249642)
							(end 0.1778 -0.2794)
						)
					)
					(width 0)
					(fill yes)
				)
			)
		)
	)
	(footprint ""
		(layer "F.Cu")
		(at 0.18034 -131.67106 180)
		(property "Reference" "C1B4"
			(at 0 0 180)
			(layer "F.SilkS")
			(hide yes)
			(effects
				(font
					(size 1.27 1.27)
				)
			)
		)
		(property "Value" ""
			(at 0 0 180)
			(layer "F.Fab")
			(effects
				(font
					(size 1.27 1.27)
				)
			)
		)
		(duplicate_pad_numbers_are_jumpers no)
		(fp_poly
			(pts
				(xy 0.3048 -0.1016) (xy 0.3048 0.9906) (xy -0.3048 0.9906) (xy -0.3048 -0.1016)
			)
			(stroke
				(width 0)
				(type default)
			)
			(fill no)
			(layer "F.CrtYd")
		)
		(fp_line
			(start 0.3048 0.9906)
			(end 0.3048 -0.1016)
			(stroke
				(width 0.1)
				(type default)
			)
			(layer "F.Fab")
		)
		(fp_line
			(start 0.3048 -0.1016)
			(end -0.3048 -0.1016)
			(stroke
				(width 0.1)
				(type default)
			)
			(layer "F.Fab")
		)
		(fp_line
			(start -0.3048 0.9906)
			(end 0.3048 0.9906)
			(stroke
				(width 0.1)
				(type default)
			)
			(layer "F.Fab")
		)
		(fp_line
			(start -0.3048 -0.1016)
			(end -0.3048 0.9906)
			(stroke
				(width 0.1)
				(type default)
			)
			(layer "F.Fab")
		)
		(pad "1" smd rect
			(at 0 0 180)
			(size 0.508 0.508)
			(layers "F.Cu" "F.Mask" "F.Paste")
			(net "PWRGD_PVDDQ_KLM_R")
		)
		(pad "2" smd rect
			(at 0 0.889 180)
			(size 0.508 0.508)
			(layers "F.Cu" "F.Mask" "F.Paste")
			(net "GND")
		)
		(zone
			(layer "F.Cu")
			(hatch none 0.5)
			(connect_pads
				(clearance 0)
			)
			(min_thickness 0.25)
			(keepout
				(tracks not_allowed)
				(vias allowed)
				(pads allowed)
				(copperpour not_allowed)
				(footprints allowed)
			)
			(placement
				(enabled no)
				(sheetname "")
			)
			(fill
				(thermal_gap 0.5)
				(thermal_bridge_width 0.5)
				(island_removal_mode 0)
			)
			(polygon
				(pts
					(xy 0.43434 -132.30606) (xy -0.07366 -132.30606) (xy -0.07366 -131.92506) (xy 0.43434 -131.92506)
				)
			)
		)
		(zone
			(layer "F.Cu")
			(hatch none 0.5)
			(connect_pads
				(clearance 0)
			)
			(min_thickness 0.25)
			(keepout
				(tracks allowed)
				(vias not_allowed)
				(pads allowed)
				(copperpour not_allowed)
				(footprints allowed)
			)
			(placement
				(enabled no)
				(sheetname "")
			)
			(fill
				(thermal_gap 0.5)
				(thermal_bridge_width 0.5)
				(island_removal_mode 0)
			)
			(polygon
				(pts
					(xy 0.43434 -131.92506) (xy -0.07366 -131.92506) (xy -0.07366 -132.30606) (xy 0.43434 -132.30606)
				)
			)
		)
	)
	(footprint ""
		(layer "F.Cu")
		(at 472.86418 -27.0764 180)
		(property "Reference" "C22W11"
			(at 0 0 180)
			(layer "F.SilkS")
			(hide yes)
			(effects
				(font
					(size 1.27 1.27)
				)
			)
		)
		(property "Value" "*"
			(at -0.0762 -6.2357 180)
			(unlocked yes)
			(layer "F.Fab")
			(hide yes)
			(effects
				(font
					(size 1.27 1.016)
					(thickness 0.1524)
				)
			)
		)
		(property "Device Type" "SC22U16V5MX-4-GP_SMD-BCG5-SC22A"
			(at -0.0762 -8.2677 180)
			(unlocked yes)
			(layer "F.Fab")
			(hide yes)
			(effects
				(font
					(size 1.27 1.016)
					(thickness 0.1524)
				)
			)
		)
		(duplicate_pad_numbers_are_jumpers no)
		(fp_line
			(start 0.635 0)
			(end -0.635 0)
			(stroke
				(width 0.508)
				(type default)
			)
			(layer "F.SilkS")
		)
		(fp_rect
			(start -0.9652 1.778)
			(end 0.9652 -1.778)
			(stroke
				(width 0)
				(type default)
			)
			(fill no)
			(layer "F.CrtYd")
		)
		(fp_poly
			(pts
				(xy -0.9652 -1.778) (xy 0.9652 -1.778) (xy 0.9652 1.778) (xy -0.9652 1.778)
			)
			(stroke
				(width 0)
				(type default)
			)
			(fill no)
			(layer "F.Fab")
		)
		(pad "1" smd rect
			(at 0 -0.9652 180)
			(size 1.397 1.143)
			(layers "F.Cu" "F.Mask" "F.Paste")
			(net "VR_FET_SW_P12V_STBY_P3V3_STBY")
		)
		(pad "2" smd rect
			(at 0 0.9652 180)
			(size 1.397 1.143)
			(layers "F.Cu" "F.Mask" "F.Paste")
			(net "GND")
		)
	)
	(footprint ""
		(layer "F.Cu")
		(at 177.927 -32.766 -90)
		(property "Reference" "C4F5"
			(at 3.32867 1.524 0)
			(unlocked yes)
			(layer "F.SilkS")
			(effects
				(font
					(size 0.7874 0.5842)
					(thickness 0.1524)
				)
			)
		)
		(property "Value" ""
			(at 0 0 270)
			(layer "F.Fab")
			(effects
				(font
					(size 1.27 1.27)
				)
			)
		)
		(duplicate_pad_numbers_are_jumpers no)
		(fp_line
			(start -2.286 7.366)
			(end -1.60147 7.366)
			(stroke
				(width 0.1524)
				(type default)
			)
			(layer "F.SilkS")
		)
		(fp_line
			(start -2.286 7.366)
			(end -2.286 1.632712)
			(stroke
				(width 0.1524)
				(type default)
			)
			(layer "F.SilkS")
		)
		(fp_line
			(start 2.286 7.366)
			(end 1.600708 7.366)
			(stroke
				(width 0.1524)
				(type default)
			)
			(layer "F.SilkS")
		)
		(fp_line
			(start 2.286 7.366)
			(end 2.286 1.63195)
			(stroke
				(width 0.1524)
				(type default)
			)
			(layer "F.SilkS")
		)
		(fp_line
			(start -2.563114 1.633982)
			(end -1.6002 1.633728)
			(stroke
				(width 0.1524)
				(type default)
			)
			(layer "F.SilkS")
		)
		(fp_line
			(start 2.504948 1.633982)
			(end 1.6002 1.633728)
			(stroke
				(width 0.1524)
				(type default)
			)
			(layer "F.SilkS")
		)
		(fp_line
			(start -2.56286 -1.616456)
			(end -2.563114 1.633982)
			(stroke
				(width 0.1524)
				(type default)
			)
			(layer "F.SilkS")
		)
		(fp_line
			(start -1.6002 -1.616456)
			(end -2.56286 -1.616456)
			(stroke
				(width 0.1524)
				(type default)
			)
			(layer "F.SilkS")
		)
		(fp_line
			(start 1.6002 -1.616456)
			(end 2.504948 -1.61671)
			(stroke
				(width 0.1524)
				(type default)
			)
			(layer "F.SilkS")
		)
		(fp_line
			(start 2.504948 -1.61671)
			(end 2.504948 1.633982)
			(stroke
				(width 0.1524)
				(type default)
			)
			(layer "F.SilkS")
		)
		(fp_rect
			(start -2.286 7.366)
			(end 2.286 -0.254)
			(stroke
				(width 0)
				(type default)
			)
			(fill no)
			(layer "F.CrtYd")
		)
		(fp_line
			(start -2.286 7.366)
			(end -2.286 -0.254)
			(stroke
				(width 0.1)
				(type default)
			)
			(layer "F.Fab")
		)
		(fp_line
			(start 2.286 7.366)
			(end -2.286 7.366)
			(stroke
				(width 0.1)
				(type default)
			)
			(layer "F.Fab")
		)
		(fp_line
			(start -2.286 -0.254)
			(end 2.286 -0.254)
			(stroke
				(width 0.1)
				(type default)
			)
			(layer "F.Fab")
		)
		(fp_line
			(start 2.286 -0.254)
			(end 2.286 7.366)
			(stroke
				(width 0.1)
				(type default)
			)
			(layer "F.Fab")
		)
		(pad "1" smd rect
			(at 0 0 270)
			(size 2.54 3.048)
			(layers "F.Cu" "F.Mask" "F.Paste")
			(net "P12V_STBY")
		)
		(pad "2" smd rect
			(at 0 7.112 270)
			(size 2.54 3.048)
			(layers "F.Cu" "F.Mask" "F.Paste")
			(net "GND")
		)
	)
	(footprint ""
		(layer "F.Cu")
		(at 390.578594 -153.47569 90)
		(property "Reference" "R8A4"
			(at 0 0 90)
			(layer "F.SilkS")
			(hide yes)
			(effects
				(font
					(size 1.27 1.27)
				)
			)
		)
		(property "Value" ""
			(at 0 0 90)
			(layer "F.Fab")
			(effects
				(font
					(size 1.27 1.27)
				)
			)
		)
		(duplicate_pad_numbers_are_jumpers no)
		(fp_poly
			(pts
				(xy -0.2794 -0.1016) (xy 0.2794 -0.1016) (xy 0.2794 0.9906) (xy -0.2794 0.9906)
			)
			(stroke
				(width 0)
				(type default)
			)
			(fill no)
			(layer "F.CrtYd")
		)
		(fp_line
			(start 0.2794 -0.1016)
			(end -0.2794 -0.1016)
			(stroke
				(width 0.1)
				(type default)
			)
			(layer "F.Fab")
		)
		(fp_line
			(start -0.2794 -0.1016)
			(end -0.2794 0.9906)
			(stroke
				(width 0.1)
				(type default)
			)
			(layer "F.Fab")
		)
		(fp_line
			(start 0.2794 0.9906)
			(end 0.2794 -0.1016)
			(stroke
				(width 0.1)
				(type default)
			)
			(layer "F.Fab")
		)
		(fp_line
			(start -0.2794 0.9906)
			(end 0.2794 0.9906)
			(stroke
				(width 0.1)
				(type default)
			)
			(layer "F.Fab")
		)
		(pad "1" smd rect
			(at 0 0 90)
			(size 0.508 0.508)
			(layers "F.Cu" "F.Mask" "F.Paste")
			(net "VR_FET_SW_P12V_STBY_PVDDQ_DEF")
		)
		(pad "2" smd rect
			(at 0 0.889 90)
			(size 0.508 0.508)
			(layers "F.Cu" "F.Mask" "F.Paste")
			(net "VR_PVNN_PCH_VINSEN")
		)
		(zone
			(layer "F.Cu")
			(hatch none 0.5)
			(connect_pads
				(clearance 0)
			)
			(min_thickness 0.25)
			(keepout
				(tracks allowed)
				(vias not_allowed)
				(pads allowed)
				(copperpour not_allowed)
				(footprints allowed)
			)
			(placement
				(enabled no)
				(sheetname "")
			)
			(fill
				(thermal_gap 0.5)
				(thermal_bridge_width 0.5)
				(island_removal_mode 0)
			)
			(polygon
				(pts
					(xy 390.832594 -153.22169) (xy 390.832594 -153.72969) (xy 391.213594 -153.72969) (xy 391.213594 -153.22169)
				)
			)
		)
		(zone
			(layer "F.Cu")
			(hatch none 0.5)
			(connect_pads
				(clearance 0)
			)
			(min_thickness 0.25)
			(keepout
				(tracks not_allowed)
				(vias allowed)
				(pads allowed)
				(copperpour not_allowed)
				(footprints allowed)
			)
			(placement
				(enabled no)
				(sheetname "")
			)
			(fill
				(thermal_gap 0.5)
				(thermal_bridge_width 0.5)
				(island_removal_mode 0)
			)
			(polygon
				(pts
					(xy 391.213594 -153.22169) (xy 391.213594 -153.72969) (xy 390.832594 -153.72969) (xy 390.832594 -153.22169)
				)
			)
		)
	)
	(footprint ""
		(layer "F.Cu")
		(at 497.781834 -23.657052 90)
		(property "Reference" "C7E5"
			(at 0 0 90)
			(layer "F.SilkS")
			(hide yes)
			(effects
				(font
					(size 1.27 1.27)
				)
			)
		)
		(property "Value" ""
			(at 0 0 90)
			(layer "F.Fab")
			(effects
				(font
					(size 1.27 1.27)
				)
			)
		)
		(duplicate_pad_numbers_are_jumpers no)
		(fp_rect
			(start 0.3048 0.9906)
			(end -0.3048 -0.1016)
			(stroke
				(width 0)
				(type default)
			)
			(fill no)
			(layer "F.CrtYd")
		)
		(fp_line
			(start 0.3048 -0.1016)
			(end -0.3048 -0.1016)
			(stroke
				(width 0.1)
				(type default)
			)
			(layer "F.Fab")
		)
		(fp_line
			(start -0.3048 -0.1016)
			(end -0.3048 0.9906)
			(stroke
				(width 0.1)
				(type default)
			)
			(layer "F.Fab")
		)
		(fp_line
			(start 0.3048 0.9906)
			(end 0.3048 -0.1016)
			(stroke
				(width 0.1)
				(type default)
			)
			(layer "F.Fab")
		)
		(fp_line
			(start -0.3048 0.9906)
			(end 0.3048 0.9906)
			(stroke
				(width 0.1)
				(type default)
			)
			(layer "F.Fab")
		)
		(pad "1" smd rect
			(at 0 0 90)
			(size 0.508 0.508)
			(layers "F.Cu" "F.Mask" "F.Paste")
			(net "P12V_STBY")
		)
		(pad "2" smd rect
			(at 0 0.889 90)
			(size 0.508 0.508)
			(layers "F.Cu" "F.Mask" "F.Paste")
			(net "GND")
		)
		(zone
			(layer "F.Cu")
			(hatch none 0.5)
			(connect_pads
				(clearance 0)
			)
			(min_thickness 0.25)
			(keepout
				(tracks allowed)
				(vias not_allowed)
				(pads allowed)
				(copperpour not_allowed)
				(footprints allowed)
			)
			(placement
				(enabled no)
				(sheetname "")
			)
			(fill
				(thermal_gap 0.5)
				(thermal_bridge_width 0.5)
				(island_removal_mode 0)
			)
			(polygon
				(pts
					(xy 498.416834 -23.911052) (xy 498.035834 -23.911052) (xy 498.035834 -23.403052) (xy 498.416834 -23.403052)
				)
			)
		)
		(zone
			(layer "F.Cu")
			(hatch none 0.5)
			(connect_pads
				(clearance 0)
			)
			(min_thickness 0.25)
			(keepout
				(tracks not_allowed)
				(vias allowed)
				(pads allowed)
				(copperpour not_allowed)
				(footprints allowed)
			)
			(placement
				(enabled no)
				(sheetname "")
			)
			(fill
				(thermal_gap 0.5)
				(thermal_bridge_width 0.5)
				(island_removal_mode 0)
			)
			(polygon
				(pts
					(xy 498.416834 -23.911052) (xy 498.035834 -23.911052) (xy 498.035834 -23.403052) (xy 498.416834 -23.403052)
				)
			)
		)
	)
	(footprint ""
		(layer "F.Cu")
		(at 19.431 -82.423 -90)
		(property "Reference" "R1D16"
			(at 0 0 270)
			(layer "F.SilkS")
			(hide yes)
			(effects
				(font
					(size 1.27 1.27)
				)
			)
		)
		(property "Value" ""
			(at 0 0 270)
			(layer "F.Fab")
			(effects
				(font
					(size 1.27 1.27)
				)
			)
		)
		(duplicate_pad_numbers_are_jumpers no)
		(fp_poly
			(pts
				(xy -0.2794 -0.1016) (xy 0.2794 -0.1016) (xy 0.2794 0.9906) (xy -0.2794 0.9906)
			)
			(stroke
				(width 0)
				(type default)
			)
			(fill no)
			(layer "F.CrtYd")
		)
		(fp_line
			(start -0.2794 0.9906)
			(end 0.2794 0.9906)
			(stroke
				(width 0.1)
				(type default)
			)
			(layer "F.Fab")
		)
		(fp_line
			(start 0.2794 0.9906)
			(end 0.2794 -0.1016)
			(stroke
				(width 0.1)
				(type default)
			)
			(layer "F.Fab")
		)
		(fp_line
			(start -0.2794 -0.1016)
			(end -0.2794 0.9906)
			(stroke
				(width 0.1)
				(type default)
			)
			(layer "F.Fab")
		)
		(fp_line
			(start 0.2794 -0.1016)
			(end -0.2794 -0.1016)
			(stroke
				(width 0.1)
				(type default)
			)
			(layer "F.Fab")
		)
		(pad "1" smd rect
			(at 0 0 270)
			(size 0.508 0.508)
			(layers "F.Cu" "F.Mask" "F.Paste")
			(net "A_HSC_ISET")
		)
		(pad "2" smd rect
			(at 0 0.889 270)
			(size 0.508 0.508)
			(layers "F.Cu" "F.Mask" "F.Paste")
			(net "A_HSC_ISET_S2")
		)
		(zone
			(layer "F.Cu")
			(hatch none 0.5)
			(connect_pads
				(clearance 0)
			)
			(min_thickness 0.25)
			(keepout
				(tracks not_allowed)
				(vias allowed)
				(pads allowed)
				(copperpour not_allowed)
				(footprints allowed)
			)
			(placement
				(enabled no)
				(sheetname "")
			)
			(fill
				(thermal_gap 0.5)
				(thermal_bridge_width 0.5)
				(island_removal_mode 0)
			)
			(polygon
				(pts
					(xy 18.796 -82.677) (xy 18.796 -82.169) (xy 19.177 -82.169) (xy 19.177 -82.677)
				)
			)
		)
		(zone
			(layer "F.Cu")
			(hatch none 0.5)
			(connect_pads
				(clearance 0)
			)
			(min_thickness 0.25)
			(keepout
				(tracks allowed)
				(vias not_allowed)
				(pads allowed)
				(copperpour not_allowed)
				(footprints allowed)
			)
			(placement
				(enabled no)
				(sheetname "")
			)
			(fill
				(thermal_gap 0.5)
				(thermal_bridge_width 0.5)
				(island_removal_mode 0)
			)
			(polygon
				(pts
					(xy 19.177 -82.677) (xy 19.177 -82.169) (xy 18.796 -82.169) (xy 18.796 -82.677)
				)
			)
		)
	)
)
